(kicad_pcb
	(version 20260206)
	(generator "pcbnew")
	(generator_version "10.0")
	(general
		(thickness 1.6)
		(legacy_teardrops no)
	)
	(paper "A4")
	(title_block
		(title "9052_F0T_PDB_Converter_Brick_F_V03_1208_1600_OCP.brd")
		(comment 1 "Grand Teton / footprints 264-270 of 578")
	)
	(layers
		(0 "F.Cu" signal "TOP")
		(4 "In1.Cu" signal "GND")
		(6 "In2.Cu" signal "IN1")
		(8 "In3.Cu" signal "GND1")
		(10 "In4.Cu" signal "VCC")
		(12 "In5.Cu" signal "VCC1")
		(14 "In6.Cu" signal "GND2")
		(16 "In7.Cu" signal "IN2")
		(18 "In8.Cu" signal "GND3")
		(2 "B.Cu" signal "BOTTOM")
		(9 "F.Adhes" user "F.Adhesive")
		(11 "B.Adhes" user "B.Adhesive")
		(13 "F.Paste" user "Package Geometry/Pastemask Top")
		(15 "B.Paste" user "Package Geometry/Pastemask Bottom")
		(5 "F.SilkS" user "Ref Des/Silkscreen Top")
		(7 "B.SilkS" user "Ref Des/Silkscreen Bottom")
		(1 "F.Mask" user "Board Geometry/Soldermask Top")
		(3 "B.Mask" user "Board Geometry/Soldermask Bottom")
		(17 "Dwgs.User" user "User.Drawings")
		(19 "Cmts.User" user "User.Comments")
		(21 "Eco1.User" user "User.Eco1")
		(23 "Eco2.User" user "User.Eco2")
		(25 "Edge.Cuts" user "Board Geometry/Outline")
		(27 "Margin" user)
		(31 "F.CrtYd" user "Package Geometry/Place Bound Top")
		(29 "B.CrtYd" user "Package Geometry/Place Bound Bottom")
		(35 "F.Fab" user "Ref Des/Assembly Top")
		(33 "B.Fab" user "Ref Des/Assembly Bottom")
	)
	(footprint ""
		(layer "F.Cu")
		(at 297.561 -119.6975 180)
		(property "Reference" "PR6958"
			(at 0 0 180)
			(layer "F.SilkS")
			(hide yes)
			(effects
				(font
					(size 1.27 1.27)
				)
			)
		)
		(property "Value" ""
			(at 0 0 180)
			(layer "F.Fab")
			(effects
				(font
					(size 1.27 1.27)
				)
			)
		)
		(duplicate_pad_numbers_are_jumpers no)
		(fp_line
			(start 1.2954 0.5842)
			(end -1.2954 0.5842)
			(stroke
				(width 0.1524)
				(type default)
			)
			(layer "F.SilkS")
		)
		(fp_line
			(start 1.2954 -0.5842)
			(end 1.2954 0.5842)
			(stroke
				(width 0.1524)
				(type default)
			)
			(layer "F.SilkS")
		)
		(fp_line
			(start -1.2954 0.5842)
			(end -1.2954 -0.5842)
			(stroke
				(width 0.1524)
				(type default)
			)
			(layer "F.SilkS")
		)
		(fp_line
			(start -1.2954 -0.5842)
			(end 1.2954 -0.5842)
			(stroke
				(width 0.1524)
				(type default)
			)
			(layer "F.SilkS")
		)
		(fp_line
			(start 1.1938 0.4064)
			(end 0.8636 0.4064)
			(stroke
				(width 0.1)
				(type default)
			)
			(layer "F.Fab")
		)
		(fp_line
			(start 1.1938 -0.406654)
			(end 1.1938 0.4064)
			(stroke
				(width 0.1)
				(type default)
			)
			(layer "F.Fab")
		)
		(fp_line
			(start 0.8636 0.4572)
			(end -0.8636 0.4572)
			(stroke
				(width 0.1)
				(type default)
			)
			(layer "F.Fab")
		)
		(fp_line
			(start 0.8636 0.4064)
			(end 0.8636 0.4572)
			(stroke
				(width 0.1)
				(type default)
			)
			(layer "F.Fab")
		)
		(fp_line
			(start 0.8636 -0.406654)
			(end 1.1938 -0.406654)
			(stroke
				(width 0.1)
				(type default)
			)
			(layer "F.Fab")
		)
		(fp_line
			(start 0.8636 -0.4572)
			(end 0.8636 -0.406654)
			(stroke
				(width 0.1)
				(type default)
			)
			(layer "F.Fab")
		)
		(fp_line
			(start -0.8636 0.4572)
			(end -0.8636 0.4318)
			(stroke
				(width 0.1)
				(type default)
			)
			(layer "F.Fab")
		)
		(fp_line
			(start -0.8636 0.4318)
			(end -0.8636 0.4064)
			(stroke
				(width 0.1)
				(type default)
			)
			(layer "F.Fab")
		)
		(fp_line
			(start -0.8636 0.4064)
			(end -1.1938 0.4064)
			(stroke
				(width 0.1)
				(type default)
			)
			(layer "F.Fab")
		)
		(fp_line
			(start -0.8636 -0.406654)
			(end -0.8636 -0.4572)
			(stroke
				(width 0.1)
				(type default)
			)
			(layer "F.Fab")
		)
		(fp_line
			(start -0.8636 -0.4572)
			(end 0.8636 -0.4572)
			(stroke
				(width 0.1)
				(type default)
			)
			(layer "F.Fab")
		)
		(fp_line
			(start -1.1938 0.4064)
			(end -1.1938 -0.406654)
			(stroke
				(width 0.1)
				(type default)
			)
			(layer "F.Fab")
		)
		(fp_line
			(start -1.1938 -0.406654)
			(end -0.8636 -0.406654)
			(stroke
				(width 0.1)
				(type default)
			)
			(layer "F.Fab")
		)
		(pad "1" smd rect
			(at -0.7366 0 90)
			(size 0.7112 0.8128)
			(layers "F.Cu" "F.Mask" "F.Paste")
			(net "P52V_HS_1272_S_N")
		)
		(pad "2" smd rect
			(at 0.7366 0 90)
			(size 0.7112 0.8128)
			(layers "F.Cu" "F.Mask" "F.Paste")
			(net "P52V_HS1_SENSE_N_R1")
		)
	)
	(footprint ""
		(layer "F.Cu")
		(at 202.654916 -67.083686 -90)
		(property "Reference" "D2"
			(at 3.202686 -0.063754 90)
			(unlocked yes)
			(layer "F.SilkS")
			(effects
				(font
					(size 0.7874 0.5842)
					(thickness 0.1524)
				)
				(justify left)
			)
		)
		(property "Value" ""
			(at 0 0 270)
			(layer "F.Fab")
			(effects
				(font
					(size 1.27 1.27)
				)
			)
		)
		(duplicate_pad_numbers_are_jumpers no)
		(fp_line
			(start -0.90678 0.4826)
			(end -0.90678 -0.4699)
			(stroke
				(width 0.1524)
				(type default)
			)
			(layer "F.SilkS")
		)
		(fp_line
			(start 0.90678 0.4826)
			(end -0.90678 0.4826)
			(stroke
				(width 0.1524)
				(type default)
			)
			(layer "F.SilkS")
		)
		(fp_line
			(start 1.03378 0.4826)
			(end -0.79248 0.4826)
			(stroke
				(width 0.1524)
				(type default)
			)
			(layer "F.SilkS")
		)
		(fp_line
			(start 1.16078 0.4826)
			(end -0.64008 0.4826)
			(stroke
				(width 0.1524)
				(type default)
			)
			(layer "F.SilkS")
		)
		(fp_line
			(start -0.89408 -0.4826)
			(end 0.90678 -0.4826)
			(stroke
				(width 0.1524)
				(type default)
			)
			(layer "F.SilkS")
		)
		(fp_line
			(start -0.79248 -0.4826)
			(end 1.03378 -0.4826)
			(stroke
				(width 0.1524)
				(type default)
			)
			(layer "F.SilkS")
		)
		(fp_line
			(start -0.64008 -0.4826)
			(end 1.16078 -0.4826)
			(stroke
				(width 0.1524)
				(type default)
			)
			(layer "F.SilkS")
		)
		(fp_line
			(start 0.90678 -0.4826)
			(end 0.90678 0.4826)
			(stroke
				(width 0.1524)
				(type default)
			)
			(layer "F.SilkS")
		)
		(fp_line
			(start 1.03378 -0.4826)
			(end 1.03378 0.4826)
			(stroke
				(width 0.1524)
				(type default)
			)
			(layer "F.SilkS")
		)
		(fp_line
			(start 1.16078 -0.4826)
			(end 1.16078 0.4826)
			(stroke
				(width 0.1524)
				(type default)
			)
			(layer "F.SilkS")
		)
		(fp_line
			(start -0.499872 0.249936)
			(end -0.499872 -0.249936)
			(stroke
				(width 0.1)
				(type default)
			)
			(layer "F.Fab")
		)
		(fp_line
			(start 0.499872 0.249936)
			(end -0.499872 0.249936)
			(stroke
				(width 0.1)
				(type default)
			)
			(layer "F.Fab")
		)
		(fp_line
			(start -0.499872 -0.249936)
			(end 0.499872 -0.249936)
			(stroke
				(width 0.1)
				(type default)
			)
			(layer "F.Fab")
		)
		(fp_line
			(start 0.499872 -0.249936)
			(end 0.499872 0.249936)
			(stroke
				(width 0.1)
				(type default)
			)
			(layer "F.Fab")
		)
		(pad "A" smd rect
			(at -0.47498 0 270)
			(size 0.6096 0.7112)
			(layers "F.Cu" "F.Mask" "F.Paste")
			(net "LED_D2_R3")
		)
		(pad "C" smd rect
			(at 0.47498 0 270)
			(size 0.6096 0.7112)
			(layers "F.Cu" "F.Mask" "F.Paste")
			(net "GND")
		)
	)
	(footprint ""
		(layer "F.Cu")
		(at 45.67936 -60.53582)
		(property "Reference" "C97"
			(at 0 0 0)
			(layer "F.SilkS")
			(hide yes)
			(effects
				(font
					(size 1.27 1.27)
				)
			)
		)
		(property "Value" ""
			(at 0 0 0)
			(layer "F.Fab")
			(effects
				(font
					(size 1.27 1.27)
				)
			)
		)
		(duplicate_pad_numbers_are_jumpers no)
		(fp_line
			(start -0.7874 -0.4064)
			(end 0.7874 -0.4064)
			(stroke
				(width 0.1524)
				(type default)
			)
			(layer "F.SilkS")
		)
		(fp_line
			(start -0.7874 0.4064)
			(end -0.7874 -0.4064)
			(stroke
				(width 0.1524)
				(type default)
			)
			(layer "F.SilkS")
		)
		(fp_line
			(start 0.7874 -0.4064)
			(end 0.7874 0.4064)
			(stroke
				(width 0.1524)
				(type default)
			)
			(layer "F.SilkS")
		)
		(fp_line
			(start 0.7874 0.4064)
			(end -0.7874 0.4064)
			(stroke
				(width 0.1524)
				(type default)
			)
			(layer "F.SilkS")
		)
		(fp_line
			(start -0.67945 -0.305054)
			(end -0.12065 -0.305054)
			(stroke
				(width 0.1)
				(type default)
			)
			(layer "F.Fab")
		)
		(fp_line
			(start -0.67945 0.3048)
			(end -0.67945 -0.305054)
			(stroke
				(width 0.1)
				(type default)
			)
			(layer "F.Fab")
		)
		(fp_line
			(start -0.12065 -0.305054)
			(end -0.12065 -0.2794)
			(stroke
				(width 0.1)
				(type default)
			)
			(layer "F.Fab")
		)
		(fp_line
			(start -0.12065 -0.2794)
			(end 0.12065 -0.2794)
			(stroke
				(width 0.1)
				(type default)
			)
			(layer "F.Fab")
		)
		(fp_line
			(start -0.12065 0.2794)
			(end -0.12065 0.3048)
			(stroke
				(width 0.1)
				(type default)
			)
			(layer "F.Fab")
		)
		(fp_line
			(start -0.12065 0.3048)
			(end -0.67945 0.3048)
			(stroke
				(width 0.1)
				(type default)
			)
			(layer "F.Fab")
		)
		(fp_line
			(start 0.120396 0.2794)
			(end -0.12065 0.2794)
			(stroke
				(width 0.1)
				(type default)
			)
			(layer "F.Fab")
		)
		(fp_line
			(start 0.120396 0.3048)
			(end 0.120396 0.2794)
			(stroke
				(width 0.1)
				(type default)
			)
			(layer "F.Fab")
		)
		(fp_line
			(start 0.12065 -0.3048)
			(end 0.67945 -0.3048)
			(stroke
				(width 0.1)
				(type default)
			)
			(layer "F.Fab")
		)
		(fp_line
			(start 0.12065 -0.2794)
			(end 0.12065 -0.3048)
			(stroke
				(width 0.1)
				(type default)
			)
			(layer "F.Fab")
		)
		(fp_line
			(start 0.67945 -0.3048)
			(end 0.67945 0.3048)
			(stroke
				(width 0.1)
				(type default)
			)
			(layer "F.Fab")
		)
		(fp_line
			(start 0.67945 0.3048)
			(end 0.120396 0.3048)
			(stroke
				(width 0.1)
				(type default)
			)
			(layer "F.Fab")
		)
		(pad "1" smd circle
			(at -0.40005 0)
			(size 0 0)
			(layers "F.Cu" "F.Mask" "F.Paste")
			(net "P12V_HPDB_0_IMON")
		)
		(pad "2" smd circle
			(at 0.40005 0)
			(size 0 0)
			(layers "F.Cu" "F.Mask" "F.Paste")
			(net "GND")
		)
	)
	(footprint ""
		(layer "F.Cu")
		(at 285.354014 -32.577024 90)
		(property "Reference" "R148"
			(at 0 0 90)
			(layer "F.SilkS")
			(hide yes)
			(effects
				(font
					(size 1.27 1.27)
				)
			)
		)
		(property "Value" ""
			(at 0 0 90)
			(layer "F.Fab")
			(effects
				(font
					(size 1.27 1.27)
				)
			)
		)
		(duplicate_pad_numbers_are_jumpers no)
		(fp_line
			(start 1.651 -0.8382)
			(end 1.651 0.8382)
			(stroke
				(width 0.1524)
				(type default)
			)
			(layer "F.SilkS")
		)
		(fp_line
			(start -1.651 -0.8382)
			(end 1.651 -0.8382)
			(stroke
				(width 0.1524)
				(type default)
			)
			(layer "F.SilkS")
		)
		(fp_line
			(start 1.651 0.8382)
			(end -1.651 0.8382)
			(stroke
				(width 0.1524)
				(type default)
			)
			(layer "F.SilkS")
		)
		(fp_line
			(start -1.651 0.8382)
			(end -1.651 -0.8382)
			(stroke
				(width 0.1524)
				(type default)
			)
			(layer "F.SilkS")
		)
		(fp_line
			(start 1.560576 -0.7366)
			(end 1.524 -0.7366)
			(stroke
				(width 0.1)
				(type default)
			)
			(layer "F.Fab")
		)
		(fp_line
			(start 1.524 -0.7366)
			(end -1.524 -0.7366)
			(stroke
				(width 0.1)
				(type default)
			)
			(layer "F.Fab")
		)
		(fp_line
			(start -1.524 -0.7366)
			(end -1.559814 -0.7366)
			(stroke
				(width 0.1)
				(type default)
			)
			(layer "F.Fab")
		)
		(fp_line
			(start -1.559814 -0.7366)
			(end -1.559814 0.7366)
			(stroke
				(width 0.1)
				(type default)
			)
			(layer "F.Fab")
		)
		(fp_line
			(start 1.560576 0.7366)
			(end 1.560576 -0.7366)
			(stroke
				(width 0.1)
				(type default)
			)
			(layer "F.Fab")
		)
		(fp_line
			(start 1.524 0.7366)
			(end 1.560576 0.7366)
			(stroke
				(width 0.1)
				(type default)
			)
			(layer "F.Fab")
		)
		(fp_line
			(start -1.524 0.7366)
			(end 1.524 0.7366)
			(stroke
				(width 0.1)
				(type default)
			)
			(layer "F.Fab")
		)
		(fp_line
			(start -1.559814 0.7366)
			(end -1.524 0.7366)
			(stroke
				(width 0.1)
				(type default)
			)
			(layer "F.Fab")
		)
		(pad "1" smd rect
			(at -0.94996 0 270)
			(size 1.1176 1.3716)
			(layers "F.Cu" "F.Mask" "F.Paste")
			(net "P52V_HS")
		)
		(pad "2" smd rect
			(at 0.94996 0 270)
			(size 1.1176 1.3716)
			(layers "F.Cu" "F.Mask" "F.Paste")
			(net "PWRGD_P52V_HS1_PG")
		)
	)
	(footprint ""
		(layer "F.Cu")
		(at 69.097906 -127.889)
		(property "Reference" "PC78"
			(at 0 0 0)
			(layer "F.SilkS")
			(hide yes)
			(effects
				(font
					(size 1.27 1.27)
				)
			)
		)
		(property "Value" ""
			(at 0 0 0)
			(layer "F.Fab")
			(effects
				(font
					(size 1.27 1.27)
				)
			)
		)
		(duplicate_pad_numbers_are_jumpers no)
		(fp_line
			(start -2.2098 -0.9398)
			(end 2.2098 -0.9398)
			(stroke
				(width 0.1524)
				(type default)
			)
			(layer "F.SilkS")
		)
		(fp_line
			(start -2.2098 0.9398)
			(end -2.2098 -0.9398)
			(stroke
				(width 0.1524)
				(type default)
			)
			(layer "F.SilkS")
		)
		(fp_line
			(start 2.2098 -0.9398)
			(end 2.2098 0.9398)
			(stroke
				(width 0.1524)
				(type default)
			)
			(layer "F.SilkS")
		)
		(fp_line
			(start 2.2098 0.9398)
			(end -2.2098 0.9398)
			(stroke
				(width 0.1524)
				(type default)
			)
			(layer "F.SilkS")
		)
		(fp_line
			(start -1.700022 -0.899922)
			(end 1.700022 -0.899922)
			(stroke
				(width 0.1)
				(type default)
			)
			(layer "F.Fab")
		)
		(fp_line
			(start -1.700022 0.899922)
			(end -1.700022 -0.899922)
			(stroke
				(width 0.1)
				(type default)
			)
			(layer "F.Fab")
		)
		(fp_line
			(start 1.700022 -0.899922)
			(end 1.700022 0.899922)
			(stroke
				(width 0.1)
				(type default)
			)
			(layer "F.Fab")
		)
		(fp_line
			(start 1.700022 0.899922)
			(end -1.700022 0.899922)
			(stroke
				(width 0.1)
				(type default)
			)
			(layer "F.Fab")
		)
		(pad "1" smd rect
			(at -1.4732 0 180)
			(size 1.1684 1.5748)
			(layers "F.Cu" "F.Mask" "F.Paste")
			(net "P52V_HS_FILTER")
		)
		(pad "2" smd rect
			(at 1.4732 0 180)
			(size 1.1684 1.5748)
			(layers "F.Cu" "F.Mask" "F.Paste")
			(net "GND")
		)
	)
	(footprint ""
		(layer "F.Cu")
		(at 174.879 -9.271 180)
		(property "Reference" "PR89"
			(at 0 0 180)
			(layer "F.SilkS")
			(hide yes)
			(effects
				(font
					(size 1.27 1.27)
				)
			)
		)
		(property "Value" ""
			(at 0 0 180)
			(layer "F.Fab")
			(effects
				(font
					(size 1.27 1.27)
				)
			)
		)
		(duplicate_pad_numbers_are_jumpers no)
		(fp_line
			(start 0.7874 0.4064)
			(end -0.7874 0.4064)
			(stroke
				(width 0.1524)
				(type default)
			)
			(layer "F.SilkS")
		)
		(fp_line
			(start 0.7874 -0.4064)
			(end 0.7874 0.4064)
			(stroke
				(width 0.1524)
				(type default)
			)
			(layer "F.SilkS")
		)
		(fp_line
			(start -0.7874 0.4064)
			(end -0.7874 -0.4064)
			(stroke
				(width 0.1524)
				(type default)
			)
			(layer "F.SilkS")
		)
		(fp_line
			(start -0.7874 -0.4064)
			(end 0.7874 -0.4064)
			(stroke
				(width 0.1524)
				(type default)
			)
			(layer "F.SilkS")
		)
		(fp_line
			(start 0.67945 0.3048)
			(end 0.120396 0.3048)
			(stroke
				(width 0.1)
				(type default)
			)
			(layer "F.Fab")
		)
		(fp_line
			(start 0.67945 -0.3048)
			(end 0.67945 0.3048)
			(stroke
				(width 0.1)
				(type default)
			)
			(layer "F.Fab")
		)
		(fp_line
			(start 0.12065 -0.2794)
			(end 0.12065 -0.3048)
			(stroke
				(width 0.1)
				(type default)
			)
			(layer "F.Fab")
		)
		(fp_line
			(start 0.12065 -0.3048)
			(end 0.67945 -0.3048)
			(stroke
				(width 0.1)
				(type default)
			)
			(layer "F.Fab")
		)
		(fp_line
			(start 0.120396 0.3048)
			(end 0.120396 0.2794)
			(stroke
				(width 0.1)
				(type default)
			)
			(layer "F.Fab")
		)
		(fp_line
			(start 0.120396 0.2794)
			(end -0.12065 0.2794)
			(stroke
				(width 0.1)
				(type default)
			)
			(layer "F.Fab")
		)
		(fp_line
			(start -0.12065 0.3048)
			(end -0.67945 0.3048)
			(stroke
				(width 0.1)
				(type default)
			)
			(layer "F.Fab")
		)
		(fp_line
			(start -0.12065 0.2794)
			(end -0.12065 0.3048)
			(stroke
				(width 0.1)
				(type default)
			)
			(layer "F.Fab")
		)
		(fp_line
			(start -0.12065 -0.2794)
			(end 0.12065 -0.2794)
			(stroke
				(width 0.1)
				(type default)
			)
			(layer "F.Fab")
		)
		(fp_line
			(start -0.12065 -0.305054)
			(end -0.12065 -0.2794)
			(stroke
				(width 0.1)
				(type default)
			)
			(layer "F.Fab")
		)
		(fp_line
			(start -0.67945 0.3048)
			(end -0.67945 -0.305054)
			(stroke
				(width 0.1)
				(type default)
			)
			(layer "F.Fab")
		)
		(fp_line
			(start -0.67945 -0.305054)
			(end -0.12065 -0.305054)
			(stroke
				(width 0.1)
				(type default)
			)
			(layer "F.Fab")
		)
		(pad "1" smd circle
			(at -0.40005 0 180)
			(size 0 0)
			(layers "F.Cu" "F.Mask" "F.Paste")
			(net "P3V3_AUX_CS")
		)
		(pad "2" smd circle
			(at 0.40005 0 180)
			(size 0 0)
			(layers "F.Cu" "F.Mask" "F.Paste")
			(net "GND")
		)
	)
	(footprint ""
		(layer "F.Cu")
		(at 43.19016 -61.93282 90)
		(property "Reference" "R5897"
			(at 0 0 90)
			(layer "F.SilkS")
			(hide yes)
			(effects
				(font
					(size 1.27 1.27)
				)
			)
		)
		(property "Value" ""
			(at 0 0 90)
			(layer "F.Fab")
			(effects
				(font
					(size 1.27 1.27)
				)
			)
		)
		(duplicate_pad_numbers_are_jumpers no)
		(fp_line
			(start 0.7874 -0.4064)
			(end 0.7874 0.4064)
			(stroke
				(width 0.1524)
				(type default)
			)
			(layer "F.SilkS")
		)
		(fp_line
			(start -0.7874 -0.4064)
			(end 0.7874 -0.4064)
			(stroke
				(width 0.1524)
				(type default)
			)
			(layer "F.SilkS")
		)
		(fp_line
			(start 0.7874 0.4064)
			(end -0.7874 0.4064)
			(stroke
				(width 0.1524)
				(type default)
			)
			(layer "F.SilkS")
		)
		(fp_line
			(start -0.7874 0.4064)
			(end -0.7874 -0.4064)
			(stroke
				(width 0.1524)
				(type default)
			)
			(layer "F.SilkS")
		)
		(fp_line
			(start -0.12065 -0.305054)
			(end -0.12065 -0.2794)
			(stroke
				(width 0.1)
				(type default)
			)
			(layer "F.Fab")
		)
		(fp_line
			(start -0.67945 -0.305054)
			(end -0.12065 -0.305054)
			(stroke
				(width 0.1)
				(type default)
			)
			(layer "F.Fab")
		)
		(fp_line
			(start 0.67945 -0.3048)
			(end 0.67945 0.3048)
			(stroke
				(width 0.1)
				(type default)
			)
			(layer "F.Fab")
		)
		(fp_line
			(start 0.12065 -0.3048)
			(end 0.67945 -0.3048)
			(stroke
				(width 0.1)
				(type default)
			)
			(layer "F.Fab")
		)
		(fp_line
			(start 0.12065 -0.2794)
			(end 0.12065 -0.3048)
			(stroke
				(width 0.1)
				(type default)
			)
			(layer "F.Fab")
		)
		(fp_line
			(start -0.12065 -0.2794)
			(end 0.12065 -0.2794)
			(stroke
				(width 0.1)
				(type default)
			)
			(layer "F.Fab")
		)
		(fp_line
			(start 0.120396 0.2794)
			(end -0.12065 0.2794)
			(stroke
				(width 0.1)
				(type default)
			)
			(layer "F.Fab")
		)
		(fp_line
			(start -0.12065 0.2794)
			(end -0.12065 0.3048)
			(stroke
				(width 0.1)
				(type default)
			)
			(layer "F.Fab")
		)
		(fp_line
			(start 0.67945 0.3048)
			(end 0.120396 0.3048)
			(stroke
				(width 0.1)
				(type default)
			)
			(layer "F.Fab")
		)
		(fp_line
			(start 0.120396 0.3048)
			(end 0.120396 0.2794)
			(stroke
				(width 0.1)
				(type default)
			)
			(layer "F.Fab")
		)
		(fp_line
			(start -0.12065 0.3048)
			(end -0.67945 0.3048)
			(stroke
				(width 0.1)
				(type default)
			)
			(layer "F.Fab")
		)
		(fp_line
			(start -0.67945 0.3048)
			(end -0.67945 -0.305054)
			(stroke
				(width 0.1)
				(type default)
			)
			(layer "F.Fab")
		)
		(pad "1" smd circle
			(at -0.40005 0 90)
			(size 0 0)
			(layers "F.Cu" "F.Mask" "F.Paste")
			(net "P12V_HPDB_0_FLTB")
		)
		(pad "2" smd circle
			(at 0.40005 0 90)
			(size 0 0)
			(layers "F.Cu" "F.Mask" "F.Paste")
			(net "P3V3_AUX")
		)
	)
)
